# ZAIUS-MB-EVT3-HW-EBOM-X00_20161228-add_2nd_source_X15-20170106-Final.xls — TBD AVL Qual (bom)
| NOTES: |  |  |  |  |  |  |
| The following items are alternates to the items listed in the Critical Components Qual tab. |  |  |  |  |  |  |
| These components will be included on near future, non-customer builds for validation and approval by both Customer and the ODM. |  |  |  |  |  |  |
| Item Description | ODM P/N | Customer PN | Vendor | Vendor PN | Build ?? | Estimated Completion Date |
| SATA connectors (black) |  |  |  |  |  |  |
| -  Alternate |  |  |  |  |  |  |
| SATA connectors (blue) |  |  |  |  |  |  |
| -  Alternate |  |  |  |  |  |  |
| PCIe retention |  |  |  |  |  |  |
| -  Alternate |  |  |  |  |  |  |
| RTC XTAL |  |  |  |  |  |  |
| -  Alternate |  |  |  |  |  |  |
| XTAL |  |  |  |  |  |  |
| -  Alternate |  |  |  |  |  |  |
